# SCM (Grand Teton) — schematic netlist excerpt (pin names and nets, part order shuffled) for the footprints in the layout excerpt that follows; sources: Cadence DE-HDL packaged netlist, KiCad conversion of 12092022_DA0F0TMDCD0_F0T_Management_Board_D_brd_V3_OCP.brd

L6  Q_INDUCTOR  BLM18PG121SN1D/2000MA IND  pkg SMLF  page 17 : \1\ = P1V0_AUX ; \2\ = P1V0_STBY_RC_VCC10A
C126  Q_CAP  22UF 6.3V 20% X6S  pkg C0603  page 16 : A = P1V8_AUX ; B = GND

(kicad_pcb
	(version 20260206)
	(generator "pcbnew")
	(generator_version "10.0")
	(general
		(thickness 1.6)
		(legacy_teardrops no)
	)
	(paper "A4")
	(title_block
		(title "12092022_DA0F0TMDCD0_F0T_Management_Board_D_brd_V3_OCP.brd")
		(comment 1 "Grand Teton / footprints 1303-1305 of 1440")
	)
	(layers
		(0 "F.Cu" signal "TOP")
		(4 "In1.Cu" signal "GND")
		(6 "In2.Cu" signal "IN1")
		(8 "In3.Cu" signal "GND1")
		(10 "In4.Cu" signal "IN2")
		(12 "In5.Cu" signal "VCC")
		(14 "In6.Cu" signal "VCC1")
		(16 "In7.Cu" signal "IN3")
		(18 "In8.Cu" signal "GND2")
		(20 "In9.Cu" signal "IN4")
		(22 "In10.Cu" signal "GND3")
		(2 "B.Cu" signal "BOTTOM")
		(9 "F.Adhes" user "F.Adhesive")
		(11 "B.Adhes" user "B.Adhesive")
		(13 "F.Paste" user "Package Geometry/Pastemask Top")
		(15 "B.Paste" user "Package Geometry/Pastemask Bottom")
		(5 "F.SilkS" user "Ref Des/Silkscreen Top")
		(7 "B.SilkS" user "Ref Des/Silkscreen Bottom")
		(1 "F.Mask" user "Board Geometry/Soldermask Top")
		(3 "B.Mask" user "Board Geometry/Soldermask Bottom")
		(17 "Dwgs.User" user "User.Drawings")
		(19 "Cmts.User" user "User.Comments")
		(21 "Eco1.User" user "User.Eco1")
		(23 "Eco2.User" user "User.Eco2")
		(25 "Edge.Cuts" user "Board Geometry/Outline")
		(27 "Margin" user)
		(31 "F.CrtYd" user "Package Geometry/Place Bound Top")
		(29 "B.CrtYd" user "Package Geometry/Place Bound Bottom")
		(35 "F.Fab" user "Ref Des/Assembly Top")
		(33 "B.Fab" user "Ref Des/Assembly Bottom")
	)
	(footprint ""
		(layer "B.Cu")
		(at 70.869556 -55.53202)
		(property "Reference" "L6"
			(at 0 0 0)
			(layer "B.SilkS")
			(hide yes)
			(effects
				(font
					(size 1.27 1.27)
				)
				(justify mirror)
			)
		)
		(property "Value" ""
			(at 0 0 0)
			(layer "B.Fab")
			(effects
				(font
					(size 1.27 1.27)
				)
				(justify mirror)
			)
		)
		(duplicate_pad_numbers_are_jumpers no)
		(fp_line
			(start -1.27 0.5842)
			(end -1.27 -0.5842)
			(stroke
				(width 0.1524)
				(type default)
			)
			(layer "B.SilkS")
		)
		(fp_line
			(start -1.27 0.5842)
			(end 1.27 0.5842)
			(stroke
				(width 0.1524)
				(type default)
			)
			(layer "B.SilkS")
		)
		(fp_line
			(start -0.127 0.5842)
			(end -0.127 -0.5842)
			(stroke
				(width 0.1524)
				(type default)
			)
			(layer "B.SilkS")
		)
		(fp_line
			(start 0.127 0.5842)
			(end 0.127 -0.5842)
			(stroke
				(width 0.1524)
				(type default)
			)
			(layer "B.SilkS")
		)
		(fp_line
			(start 1.27 -0.5842)
			(end -1.27 -0.5842)
			(stroke
				(width 0.1524)
				(type default)
			)
			(layer "B.SilkS")
		)
		(fp_line
			(start 1.27 -0.5588)
			(end 1.27 -0.5842)
			(stroke
				(width 0.1524)
				(type default)
			)
			(layer "B.SilkS")
		)
		(fp_line
			(start 1.27 0.5842)
			(end 1.27 -0.5842)
			(stroke
				(width 0.1524)
				(type default)
			)
			(layer "B.SilkS")
		)
		(fp_line
			(start -1.1938 -0.406654)
			(end -1.1938 0.4064)
			(stroke
				(width 0.1)
				(type default)
			)
			(layer "B.Fab")
		)
		(fp_line
			(start -1.1938 0.4064)
			(end -0.9144 0.4064)
			(stroke
				(width 0.1)
				(type default)
			)
			(layer "B.Fab")
		)
		(fp_line
			(start -0.9144 -0.508)
			(end -0.9144 -0.406654)
			(stroke
				(width 0.1)
				(type default)
			)
			(layer "B.Fab")
		)
		(fp_line
			(start -0.9144 -0.406654)
			(end -1.1938 -0.406654)
			(stroke
				(width 0.1)
				(type default)
			)
			(layer "B.Fab")
		)
		(fp_line
			(start -0.9144 0.4064)
			(end -0.9144 0.508)
			(stroke
				(width 0.1)
				(type default)
			)
			(layer "B.Fab")
		)
		(fp_line
			(start -0.9144 0.508)
			(end 0.9144 0.508)
			(stroke
				(width 0.1)
				(type default)
			)
			(layer "B.Fab")
		)
		(fp_line
			(start 0.9144 -0.508)
			(end -0.9144 -0.508)
			(stroke
				(width 0.1)
				(type default)
			)
			(layer "B.Fab")
		)
		(fp_line
			(start 0.9144 -0.406654)
			(end 0.9144 -0.508)
			(stroke
				(width 0.1)
				(type default)
			)
			(layer "B.Fab")
		)
		(fp_line
			(start 0.9144 0.406654)
			(end 1.194308 0.406654)
			(stroke
				(width 0.1)
				(type default)
			)
			(layer "B.Fab")
		)
		(fp_line
			(start 0.9144 0.508)
			(end 0.9144 0.406654)
			(stroke
				(width 0.1)
				(type default)
			)
			(layer "B.Fab")
		)
		(fp_line
			(start 1.194308 -0.406654)
			(end 0.9144 -0.406654)
			(stroke
				(width 0.1)
				(type default)
			)
			(layer "B.Fab")
		)
		(fp_line
			(start 1.194308 0.406654)
			(end 1.194308 -0.406654)
			(stroke
				(width 0.1)
				(type default)
			)
			(layer "B.Fab")
		)
		(pad "1" smd rect
			(at 0.7366 0 270)
			(size 0.7112 0.8128)
			(layers "B.Cu" "B.Mask" "B.Paste")
			(net "P1V0_AUX")
		)
		(pad "2" smd rect
			(at -0.7366 0 270)
			(size 0.7112 0.8128)
			(layers "B.Cu" "B.Mask" "B.Paste")
			(net "P1V0_STBY_RC_VCC10A")
		)
	)
	(footprint ""
		(layer "B.Cu")
		(at 8.001 -112.649)
		(property "Reference" ""
			(at 0 0 0)
			(layer "B.SilkS")
			(hide yes)
			(effects
				(font
					(size 1.27 1.27)
				)
				(justify mirror)
			)
		)
		(property "Value" ""
			(at 0 0 0)
			(layer "B.Fab")
			(effects
				(font
					(size 1.27 1.27)
				)
				(justify mirror)
			)
		)
		(duplicate_pad_numbers_are_jumpers no)
		(pad "1" smd circle
			(at 0 0 180)
			(size 0.9906 0.9906)
			(layers "B.Cu" "B.Mask" "B.Paste")
			(net "Net_598")
		)
		(zone
			(layer "B.Cu")
			(hatch none 0.5)
			(connect_pads
				(clearance 0)
			)
			(min_thickness 0.25)
			(keepout
				(tracks not_allowed)
				(vias allowed)
				(pads allowed)
				(copperpour not_allowed)
				(footprints allowed)
			)
			(placement
				(enabled no)
				(sheetname "")
			)
			(fill
				(thermal_gap 0.5)
				(thermal_bridge_width 0.5)
				(island_removal_mode 0)
			)
			(polygon
				(pts
					(arc
						(start 9.6266 -112.649)
						(mid 6.3754 -112.649)
						(end 9.6266 -112.649)
					)
				)
			)
		)
	)
	(footprint ""
		(layer "B.Cu")
		(at 70.543674 -37.05479 90)
		(property "Reference" "C126"
			(at 0 0 90)
			(layer "B.SilkS")
			(hide yes)
			(effects
				(font
					(size 1.27 1.27)
				)
				(justify mirror)
			)
		)
		(property "Value" ""
			(at 0 0 90)
			(layer "B.Fab")
			(effects
				(font
					(size 1.27 1.27)
				)
				(justify mirror)
			)
		)
		(duplicate_pad_numbers_are_jumpers no)
		(fp_line
			(start 1.2954 -0.5842)
			(end -1.2954 -0.5842)
			(stroke
				(width 0.1524)
				(type default)
			)
			(layer "B.SilkS")
		)
		(fp_line
			(start 0 -0.5842)
			(end 0 0.5842)
			(stroke
				(width 0.1524)
				(type default)
			)
			(layer "B.SilkS")
		)
		(fp_line
			(start -1.2954 -0.5842)
			(end -1.2954 0.5842)
			(stroke
				(width 0.1524)
				(type default)
			)
			(layer "B.SilkS")
		)
		(fp_line
			(start 1.2954 0.5842)
			(end 1.2954 -0.5842)
			(stroke
				(width 0.1524)
				(type default)
			)
			(layer "B.SilkS")
		)
		(fp_line
			(start -1.2954 0.5842)
			(end 1.2954 0.5842)
			(stroke
				(width 0.1524)
				(type default)
			)
			(layer "B.SilkS")
		)
		(fp_line
			(start 0.8636 -0.4572)
			(end -0.8636 -0.4572)
			(stroke
				(width 0.1)
				(type default)
			)
			(layer "B.Fab")
		)
		(fp_line
			(start -0.8636 -0.4572)
			(end -0.8636 -0.4064)
			(stroke
				(width 0.1)
				(type default)
			)
			(layer "B.Fab")
		)
		(fp_line
			(start 1.1938 -0.4064)
			(end 0.8636 -0.4064)
			(stroke
				(width 0.1)
				(type default)
			)
			(layer "B.Fab")
		)
		(fp_line
			(start 0.8636 -0.4064)
			(end 0.8636 -0.4572)
			(stroke
				(width 0.1)
				(type default)
			)
			(layer "B.Fab")
		)
		(fp_line
			(start -0.8636 -0.4064)
			(end -1.1938 -0.4064)
			(stroke
				(width 0.1)
				(type default)
			)
			(layer "B.Fab")
		)
		(fp_line
			(start -1.1938 -0.4064)
			(end -1.1938 0.4064)
			(stroke
				(width 0.1)
				(type default)
			)
			(layer "B.Fab")
		)
		(fp_line
			(start 1.1938 0.4064)
			(end 1.1938 -0.4064)
			(stroke
				(width 0.1)
				(type default)
			)
			(layer "B.Fab")
		)
		(fp_line
			(start 0.8636 0.4064)
			(end 1.1938 0.4064)
			(stroke
				(width 0.1)
				(type default)
			)
			(layer "B.Fab")
		)
		(fp_line
			(start -0.8636 0.4064)
			(end -0.8636 0.4572)
			(stroke
				(width 0.1)
				(type default)
			)
			(layer "B.Fab")
		)
		(fp_line
			(start -1.1938 0.4064)
			(end -0.8636 0.4064)
			(stroke
				(width 0.1)
				(type default)
			)
			(layer "B.Fab")
		)
		(fp_line
			(start 0.8636 0.4572)
			(end 0.8636 0.4064)
			(stroke
				(width 0.1)
				(type default)
			)
			(layer "B.Fab")
		)
		(fp_line
			(start -0.8636 0.4572)
			(end 0.8636 0.4572)
			(stroke
				(width 0.1)
				(type default)
			)
			(layer "B.Fab")
		)
		(pad "1" smd rect
			(at 0.7366 0)
			(size 0.7112 0.8128)
			(layers "B.Cu" "B.Mask" "B.Paste")
			(net "P1V8_AUX")
		)
		(pad "2" smd rect
			(at -0.7366 0)
			(size 0.7112 0.8128)
			(layers "B.Cu" "B.Mask" "B.Paste")
			(net "GND")
		)
	)
)
